# G2-Thermal part_DVT_20170807-update.xlsx — G2 (thermal-test-report)
| Item | Description | Vendor | MFG P/N | Foxconn P/N | rev | Drawing | remark |
| 1 | CPU HSK | Forcecon | 0TJLQ0000H | 460405U00-21M-G | X00 |  |  |
|  |  | Foxconn T1 | PHPG78GX0012 |  | A |  |  |
| 2 | GV100 GPU HSK | Foxconn T1 | PHG199GB0012 | 460406400-600-G | A |  |  |
|  |  | Forcecon | 0TJJD0000H | 460405Y00-21M-G | X00 |  |  |
| 3 | Expandar HSK | Foxconn T1 | PHCM79X02012 | 48011V500-600-G | X00 |  |  |
|  |  | Forcecon | 0RJLK0000H | 480120400-21M-G | X00 |  |  |
| 4 | System Fan 6056 | Sunon | PF60561Bx-D090-S9H | 490206P00-H17-G | X01 |  |  |
| 5 | VTM HSK-1 (40x80x10 mm) | AAVID | 654427 | 480120V00-13E-G | A |  |  |
|  |  | Furukawa | HS855361 | 480120700-H8U-G | E |  |  |
| 6 | VTM HSK-2 (80x57.3x15 mm) | AAVID | 654428 | 480120U00-13E-G | A |  |  |
|  |  | Furukawa | HS855371 | 480120800-H8U-G | E |  |  |
| 7 | PLX9797 HSK | Foxconn T1 | PHCN58GX0012 | 480120S00-600-G | X1 |  |  |
